(kicad_pcb
	(version 20260206)
	(generator "pcbnew")
	(generator_version "10.0")
	(general
		(thickness 1.21888)
		(legacy_teardrops no)
	)
	(paper "A4")
	(title_block
		(title "timecard-v8 — TimeCard-DC-V8_EXP.PcbDoc")
		(comment 1 "Time Appliance Project (Time Card) / footprints 222-224 of 288")
	)
	(layers
		(0 "F.Cu" signal "TOP")
		(4 "In1.Cu" signal "SGND")
		(6 "In2.Cu" signal "IN1")
		(8 "In3.Cu" signal "IN2")
		(10 "In4.Cu" signal "SGND1")
		(2 "B.Cu" signal "BOTTOM")
		(9 "F.Adhes" user "F.Adhesive")
		(11 "B.Adhes" user "B.Adhesive")
		(13 "F.Paste" user "Top Paste")
		(15 "B.Paste" user "Bottom Paste")
		(5 "F.SilkS" user "Top Overlay")
		(7 "B.SilkS" user "Bottom Overlay")
		(1 "F.Mask" user "Top Solder")
		(3 "B.Mask" user "Bottom Solder")
		(17 "Dwgs.User" user "User.Drawings")
		(19 "Cmts.User" user "User.Comments")
		(21 "Eco1.User" user "User.Eco1")
		(23 "Eco2.User" user "User.Eco2")
		(25 "Edge.Cuts" user)
		(27 "Margin" user)
		(31 "F.CrtYd" user "Top Courtyard")
		(29 "B.CrtYd" user "Bottom Courtyard")
		(35 "F.Fab" user "Top Component Center")
		(33 "B.Fab" user "Bottom Component Center")
	)
	(footprint "Vault:FP-BNO055-MFG"
		(layer "F.Cu")
		(at 187.3261 86.2162 -90)
		(property "Reference" "U13"
			(at 3.126931 1.3714 0)
			(unlocked yes)
			(layer "F.SilkS")
			(effects
				(font
					(size 0.762 0.762)
					(thickness 0.2286)
				)
			)
		)
		(property "Value" "BNO055"
			(at 1.94174 3.494271 270)
			(unlocked yes)
			(layer "F.SilkS")
			(hide yes)
			(effects
				(font
					(size 0.762 0.762)
					(thickness 0.2286)
				)
			)
		)
		(sheetname "GPS_IMU_SENSORS")
		(sheetfile "GPS_IMU_SENSORS.kicad_sch")
		(duplicate_pad_numbers_are_jumpers no)
		(fp_rect
			(start -0.400005 2.575005)
			(end -0.100005 2.049995)
			(stroke
				(width 0)
				(type default)
			)
			(fill yes)
			(layer "F.Mask")
		)
		(fp_rect
			(start -0.9 2.575)
			(end -0.6 2.05)
			(stroke
				(width 0)
				(type default)
			)
			(fill yes)
			(layer "F.Mask")
		)
		(fp_rect
			(start 0.09999 2.575)
			(end 0.39999 2.05)
			(stroke
				(width 0)
				(type default)
			)
			(fill yes)
			(layer "F.Mask")
		)
		(fp_rect
			(start 0.6 2.575)
			(end 0.9 2.05)
			(stroke
				(width 0)
				(type default)
			)
			(fill yes)
			(layer "F.Mask")
		)
		(fp_rect
			(start -1.82501 2.45001)
			(end -1.30001 2.05001)
			(stroke
				(width 0)
				(type default)
			)
			(fill yes)
			(layer "F.Mask")
		)
		(fp_rect
			(start 1.3 2.44999)
			(end 1.825 2.04999)
			(stroke
				(width 0)
				(type default)
			)
			(fill yes)
			(layer "F.Mask")
		)
		(fp_rect
			(start -1.825005 1.950005)
			(end -1.300005 1.549995)
			(stroke
				(width 0)
				(type default)
			)
			(fill yes)
			(layer "F.Mask")
		)
		(fp_rect
			(start 1.299995 1.950005)
			(end 1.824995 1.549995)
			(stroke
				(width 0)
				(type default)
			)
			(fill yes)
			(layer "F.Mask")
		)
		(fp_rect
			(start 1.29999 1.45001)
			(end 1.82499 1.05001)
			(stroke
				(width 0)
				(type default)
			)
			(fill yes)
			(layer "F.Mask")
		)
		(fp_rect
			(start -1.825 1.44999)
			(end -1.3 1.04999)
			(stroke
				(width 0)
				(type default)
			)
			(fill yes)
			(layer "F.Mask")
		)
		(fp_rect
			(start -1.825005 0.950005)
			(end -1.300005 0.549995)
			(stroke
				(width 0)
				(type default)
			)
			(fill yes)
			(layer "F.Mask")
		)
		(fp_rect
			(start 1.299995 0.950005)
			(end 1.824995 0.549995)
			(stroke
				(width 0)
				(type default)
			)
			(fill yes)
			(layer "F.Mask")
		)
		(fp_rect
			(start -1.82501 0.45001)
			(end -1.30001 0.05001)
			(stroke
				(width 0)
				(type default)
			)
			(fill yes)
			(layer "F.Mask")
		)
		(fp_rect
			(start 1.3 0.44999)
			(end 1.825 0.04999)
			(stroke
				(width 0)
				(type default)
			)
			(fill yes)
			(layer "F.Mask")
		)
		(fp_rect
			(start -1.82501 -0.04999)
			(end -1.30001 -0.44999)
			(stroke
				(width 0)
				(type default)
			)
			(fill yes)
			(layer "F.Mask")
		)
		(fp_rect
			(start 1.3 -0.05001)
			(end 1.825 -0.45001)
			(stroke
				(width 0)
				(type default)
			)
			(fill yes)
			(layer "F.Mask")
		)
		(fp_rect
			(start -1.825005 -0.549995)
			(end -1.300005 -0.950005)
			(stroke
				(width 0)
				(type default)
			)
			(fill yes)
			(layer "F.Mask")
		)
		(fp_rect
			(start 1.299995 -0.549995)
			(end 1.824995 -0.950005)
			(stroke
				(width 0)
				(type default)
			)
			(fill yes)
			(layer "F.Mask")
		)
		(fp_rect
			(start 1.29999 -1.04999)
			(end 1.82499 -1.44999)
			(stroke
				(width 0)
				(type default)
			)
			(fill yes)
			(layer "F.Mask")
		)
		(fp_rect
			(start -1.825 -1.05001)
			(end -1.3 -1.45001)
			(stroke
				(width 0)
				(type default)
			)
			(fill yes)
			(layer "F.Mask")
		)
		(fp_rect
			(start -1.825005 -1.549995)
			(end -1.300005 -1.950005)
			(stroke
				(width 0)
				(type default)
			)
			(fill yes)
			(layer "F.Mask")
		)
		(fp_rect
			(start 1.299995 -1.549995)
			(end 1.824995 -1.950005)
			(stroke
				(width 0)
				(type default)
			)
			(fill yes)
			(layer "F.Mask")
		)
		(fp_rect
			(start -1.82501 -2.04999)
			(end -1.30001 -2.44999)
			(stroke
				(width 0)
				(type default)
			)
			(fill yes)
			(layer "F.Mask")
		)
		(fp_rect
			(start -0.400005 -2.049995)
			(end -0.100005 -2.575005)
			(stroke
				(width 0)
				(type default)
			)
			(fill yes)
			(layer "F.Mask")
		)
		(fp_rect
			(start -0.9 -2.05)
			(end -0.6 -2.575)
			(stroke
				(width 0)
				(type default)
			)
			(fill yes)
			(layer "F.Mask")
		)
		(fp_rect
			(start 0.09999 -2.05)
			(end 0.39999 -2.575)
			(stroke
				(width 0)
				(type default)
			)
			(fill yes)
			(layer "F.Mask")
		)
		(fp_rect
			(start 0.6 -2.05)
			(end 0.9 -2.575)
			(stroke
				(width 0)
				(type default)
			)
			(fill yes)
			(layer "F.Mask")
		)
		(fp_rect
			(start 1.3 -2.05001)
			(end 1.825 -2.45001)
			(stroke
				(width 0)
				(type default)
			)
			(fill yes)
			(layer "F.Mask")
		)
		(fp_line
			(start -2.25 2.65)
			(end -2.25 -2.65)
			(stroke
				(width 0.2)
				(type solid)
			)
			(layer "F.SilkS")
		)
		(fp_line
			(start 2.25 2.65)
			(end 2.25 -2.65)
			(stroke
				(width 0.2)
				(type solid)
			)
			(layer "F.SilkS")
		)
		(fp_circle
			(center 2.75 -2.25)
			(end 2.625 -2.25)
			(stroke
				(width 0.25)
				(type solid)
			)
			(fill no)
			(layer "F.SilkS")
		)
		(fp_line
			(start -2.45 3.15)
			(end -2.45 -3.15)
			(stroke
				(width 0.2)
				(type solid)
			)
			(layer "F.CrtYd")
		)
		(fp_line
			(start 2.45 3.15)
			(end -2.45 3.15)
			(stroke
				(width 0.2)
				(type solid)
			)
			(layer "F.CrtYd")
		)
		(fp_line
			(start 2.45 3.15)
			(end 2.45 -3.15)
			(stroke
				(width 0.2)
				(type solid)
			)
			(layer "F.CrtYd")
		)
		(fp_line
			(start 2.45 -3.15)
			(end -2.45 -3.15)
			(stroke
				(width 0.2)
				(type solid)
			)
			(layer "F.CrtYd")
		)
		(fp_line
			(start -2.45 3.15)
			(end -2.45 -3.15)
			(stroke
				(width 0.2)
				(type solid)
			)
			(layer "F.Fab")
		)
		(fp_line
			(start 2.45 3.15)
			(end -2.45 3.15)
			(stroke
				(width 0.2)
				(type solid)
			)
			(layer "F.Fab")
		)
		(fp_line
			(start 2.45 3.15)
			(end 2.45 -3.15)
			(stroke
				(width 0.2)
				(type solid)
			)
			(layer "F.Fab")
		)
		(fp_line
			(start 0 0.735)
			(end 0 -0.735)
			(stroke
				(width 0.1)
				(type solid)
			)
			(layer "F.Fab")
		)
		(fp_line
			(start 0.735 0)
			(end -0.735 0)
			(stroke
				(width 0.1)
				(type solid)
			)
			(layer "F.Fab")
		)
		(fp_line
			(start 2.45 -3.15)
			(end -2.45 -3.15)
			(stroke
				(width 0.2)
				(type solid)
			)
			(layer "F.Fab")
		)
		(fp_text user "${REFERENCE}"
			(at 0 0.28425 270)
			(unlocked yes)
			(layer "F.Fab")
			(effects
				(font
					(face "Arial")
					(size 0.63 0.63)
					(thickness 0.1)
				)
				(justify left bottom)
			)
		)
		(pad "1" smd rect
			(at 1.5625 -2.25 270)
			(size 0.475 0.35)
			(layers "F.Cu" "F.Mask" "F.Paste")
			(solder_mask_margin -1000)
			(solder_paste_margin 0)
		)
		(pad "2" smd rect
			(at 0.75 -2.3125 270)
			(size 0.25 0.475)
			(layers "F.Cu" "F.Mask" "F.Paste")
			(net "GND")
			(solder_mask_margin -1000)
			(solder_paste_margin 0)
		)
		(pad "3" smd rect
			(at 0.25 -2.3125 270)
			(size 0.25 0.475)
			(layers "F.Cu" "F.Mask" "F.Paste")
			(net "+3.3V")
			(solder_mask_margin -1000)
			(solder_paste_margin 0)
		)
		(pad "4" smd rect
			(at -0.25 -2.3125 270)
			(size 0.25 0.475)
			(layers "F.Cu" "F.Mask" "F.Paste")
			(net "NetR51_2")
			(solder_mask_margin -1000)
			(solder_paste_margin 0)
		)
		(pad "5" smd rect
			(at -0.75 -2.3125 270)
			(size 0.25 0.475)
			(layers "F.Cu" "F.Mask" "F.Paste")
			(net "GND")
			(solder_mask_margin -1000)
			(solder_paste_margin 0)
		)
		(pad "6" smd rect
			(at -1.5625 -2.25 270)
			(size 0.475 0.35)
			(layers "F.Cu" "F.Mask" "F.Paste")
			(net "GND")
			(solder_mask_margin -1000)
			(solder_paste_margin 0)
		)
		(pad "7" smd rect
			(at -1.5625 -1.75 270)
			(size 0.475 0.35)
			(layers "F.Cu" "F.Mask" "F.Paste")
			(net "NetR57_2")
			(solder_mask_margin -1000)
			(solder_paste_margin 0)
		)
		(pad "8" smd rect
			(at -1.5625 -1.25 270)
			(size 0.475 0.35)
			(layers "F.Cu" "F.Mask" "F.Paste")
			(net "NetR58_2")
			(solder_mask_margin -1000)
			(solder_paste_margin 0)
		)
		(pad "9" smd rect
			(at -1.5625 -0.75 270)
			(size 0.475 0.35)
			(layers "F.Cu" "F.Mask" "F.Paste")
			(net "NetC65_1")
			(solder_mask_margin -1000)
			(solder_paste_margin 0)
		)
		(pad "10" smd rect
			(at -1.5625 -0.25 270)
			(size 0.475 0.35)
			(layers "F.Cu" "F.Mask" "F.Paste")
			(net "NetR55_2")
			(solder_mask_margin -1000)
			(solder_paste_margin 0)
		)
		(pad "11" smd rect
			(at -1.5625 0.25 270)
			(size 0.475 0.35)
			(layers "F.Cu" "F.Mask" "F.Paste")
			(net "NetR52_1")
			(solder_mask_margin -1000)
			(solder_paste_margin 0)
		)
		(pad "12" smd rect
			(at -1.5625 0.75 270)
			(size 0.475 0.35)
			(layers "F.Cu" "F.Mask" "F.Paste")
			(solder_mask_margin -1000)
			(solder_paste_margin 0)
		)
		(pad "13" smd rect
			(at -1.5625 1.25 270)
			(size 0.475 0.35)
			(layers "F.Cu" "F.Mask" "F.Paste")
			(solder_mask_margin -1000)
			(solder_paste_margin 0)
		)
		(pad "14" smd rect
			(at -1.5625 1.75 270)
			(size 0.475 0.35)
			(layers "F.Cu" "F.Mask" "F.Paste")
			(net "BNO_INT")
			(solder_mask_margin -1000)
			(solder_paste_margin 0)
		)
		(pad "15" smd rect
			(at -1.5625 2.25 270)
			(size 0.475 0.35)
			(layers "F.Cu" "F.Mask" "F.Paste")
			(solder_mask_margin -1000)
			(solder_paste_margin 0)
		)
		(pad "16" smd rect
			(at -0.75 2.3125 270)
			(size 0.25 0.475)
			(layers "F.Cu" "F.Mask" "F.Paste")
			(solder_mask_margin -1000)
			(solder_paste_margin 0)
		)
		(pad "17" smd rect
			(at -0.25 2.3125 270)
			(size 0.25 0.475)
			(layers "F.Cu" "F.Mask" "F.Paste")
			(net "NetR53_1")
			(solder_mask_margin -1000)
			(solder_paste_margin 0)
		)
		(pad "18" smd rect
			(at 0.25 2.3125 270)
			(size 0.25 0.475)
			(layers "F.Cu" "F.Mask" "F.Paste")
			(net "GND")
			(solder_mask_margin -1000)
			(solder_paste_margin 0)
		)
		(pad "19" smd rect
			(at 0.75 2.3125 270)
			(size 0.25 0.475)
			(layers "F.Cu" "F.Mask" "F.Paste")
			(net "SCL")
			(solder_mask_margin -1000)
			(solder_paste_margin 0)
		)
		(pad "20" smd rect
			(at 1.5625 2.25 270)
			(size 0.475 0.35)
			(layers "F.Cu" "F.Mask" "F.Paste")
			(net "SDA")
			(solder_mask_margin -1000)
			(solder_paste_margin 0)
		)
		(pad "21" smd rect
			(at 1.5625 1.75 270)
			(size 0.475 0.35)
			(layers "F.Cu" "F.Mask" "F.Paste")
			(solder_mask_margin -1000)
			(solder_paste_margin 0)
		)
		(pad "22" smd rect
			(at 1.5625 1.25 270)
			(size 0.475 0.35)
			(layers "F.Cu" "F.Mask" "F.Paste")
			(solder_mask_margin -1000)
			(solder_paste_margin 0)
		)
		(pad "23" smd rect
			(at 1.5625 0.75 270)
			(size 0.475 0.35)
			(layers "F.Cu" "F.Mask" "F.Paste")
			(solder_mask_margin -1000)
			(solder_paste_margin 0)
		)
		(pad "24" smd rect
			(at 1.5625 0.25 270)
			(size 0.475 0.35)
			(layers "F.Cu" "F.Mask" "F.Paste")
			(solder_mask_margin -1000)
			(solder_paste_margin 0)
		)
		(pad "25" smd rect
			(at 1.5625 -0.25 270)
			(size 0.475 0.35)
			(layers "F.Cu" "F.Mask" "F.Paste")
			(net "GND")
			(solder_mask_margin -1000)
			(solder_paste_margin 0)
		)
		(pad "26" smd rect
			(at 1.5625 -0.75 270)
			(size 0.475 0.35)
			(layers "F.Cu" "F.Mask" "F.Paste")
			(net "BNO_XOUT32")
			(solder_mask_margin -1000)
			(solder_paste_margin 0)
		)
		(pad "27" smd rect
			(at 1.5625 -1.25 270)
			(size 0.475 0.35)
			(layers "F.Cu" "F.Mask" "F.Paste")
			(net "BNO_XIN32")
			(solder_mask_margin -1000)
			(solder_paste_margin 0)
		)
		(pad "28" smd rect
			(at 1.5625 -1.75 270)
			(size 0.475 0.35)
			(layers "F.Cu" "F.Mask" "F.Paste")
			(net "+3.3V")
			(solder_mask_margin -1000)
			(solder_paste_margin 0)
		)
	)
	(footprint "Vault:FP-BME280-MFG"
		(layer "F.Cu")
		(at 194.1261 86.8286)
		(property "Reference" "U14"
			(at 0.926931 2.759 90)
			(unlocked yes)
			(layer "F.SilkS")
			(effects
				(font
					(size 0.762 0.762)
					(thickness 0.2286)
				)
			)
		)
		(property "Value" "BME280"
			(at 2.9069 3.443471 0)
			(unlocked yes)
			(layer "F.SilkS")
			(hide yes)
			(effects
				(font
					(size 0.762 0.762)
					(thickness 0.2286)
				)
			)
		)
		(sheetname "GPS_IMU_SENSORS")
		(sheetfile "GPS_IMU_SENSORS.kicad_sch")
		(duplicate_pad_numbers_are_jumpers no)
		(fp_line
			(start -1.3 -1.55)
			(end 1.3 -1.55)
			(stroke
				(width 0.2)
				(type solid)
			)
			(layer "F.SilkS")
		)
		(fp_line
			(start -1.3 1.55)
			(end 1.3 1.55)
			(stroke
				(width 0.2)
				(type solid)
			)
			(layer "F.SilkS")
		)
		(fp_circle
			(center 1.85 -0.975)
			(end 1.85 -1.1)
			(stroke
				(width 0.25)
				(type solid)
			)
			(fill no)
			(layer "F.SilkS")
		)
		(fp_line
			(start -1.8 -1.8)
			(end 1.8 -1.8)
			(stroke
				(width 0.2)
				(type solid)
			)
			(layer "F.CrtYd")
		)
		(fp_line
			(start -1.8 1.8)
			(end -1.8 -1.8)
			(stroke
				(width 0.2)
				(type solid)
			)
			(layer "F.CrtYd")
		)
		(fp_line
			(start -1.8 1.8)
			(end 1.8 1.8)
			(stroke
				(width 0.2)
				(type solid)
			)
			(layer "F.CrtYd")
		)
		(fp_line
			(start 1.8 1.8)
			(end 1.8 -1.8)
			(stroke
				(width 0.2)
				(type solid)
			)
			(layer "F.CrtYd")
		)
		(fp_line
			(start -1.8 -1.8)
			(end 1.8 -1.8)
			(stroke
				(width 0.2)
				(type solid)
			)
			(layer "F.Fab")
		)
		(fp_line
			(start -1.8 1.8)
			(end -1.8 -1.8)
			(stroke
				(width 0.2)
				(type solid)
			)
			(layer "F.Fab")
		)
		(fp_line
			(start -1.8 1.8)
			(end 1.8 1.8)
			(stroke
				(width 0.2)
				(type solid)
			)
			(layer "F.Fab")
		)
		(fp_line
			(start -0.5 0)
			(end 0.5 0)
			(stroke
				(width 0.1)
				(type solid)
			)
			(layer "F.Fab")
		)
		(fp_line
			(start 0 0.5)
			(end 0 -0.5)
			(stroke
				(width 0.1)
				(type solid)
			)
			(layer "F.Fab")
		)
		(fp_line
			(start 1.8 1.8)
			(end 1.8 -1.8)
			(stroke
				(width 0.2)
				(type solid)
			)
			(layer "F.Fab")
		)
		(fp_text user "${REFERENCE}"
			(at 0 0.28425 0)
			(unlocked yes)
			(layer "F.Fab")
			(effects
				(font
					(face "Arial")
					(size 0.63 0.63)
					(thickness 0.1)
				)
				(justify left bottom)
			)
		)
		(pad "1" smd rect
			(at 1.025 -0.975)
			(size 0.5 0.35)
			(layers "F.Cu" "F.Mask" "F.Paste")
			(net "GND")
			(solder_mask_margin 0)
			(solder_paste_margin 0)
		)
		(pad "2" smd rect
			(at 1.025 -0.325)
			(size 0.5 0.35)
			(layers "F.Cu" "F.Mask" "F.Paste")
			(net "+3.3V")
			(solder_mask_margin 0)
			(solder_paste_margin 0)
		)
		(pad "3" smd rect
			(at 1.025 0.325)
			(size 0.5 0.35)
			(layers "F.Cu" "F.Mask" "F.Paste")
			(net "SDA")
			(solder_mask_margin 0)
			(solder_paste_margin 0)
		)
		(pad "4" smd rect
			(at 1.025 0.975)
			(size 0.5 0.35)
			(layers "F.Cu" "F.Mask" "F.Paste")
			(net "SCL")
			(solder_mask_margin 0)
			(solder_paste_margin 0)
		)
		(pad "5" smd rect
			(at -1.025 0.975)
			(size 0.5 0.35)
			(layers "F.Cu" "F.Mask" "F.Paste")
			(net "GND")
			(solder_mask_margin 0)
			(solder_paste_margin 0)
		)
		(pad "6" smd rect
			(at -1.025 0.325)
			(size 0.5 0.35)
			(layers "F.Cu" "F.Mask" "F.Paste")
			(net "+3.3V")
			(solder_mask_margin 0)
			(solder_paste_margin 0)
		)
		(pad "7" smd rect
			(at -1.025 -0.325)
			(size 0.5 0.35)
			(layers "F.Cu" "F.Mask" "F.Paste")
			(net "GND")
			(solder_mask_margin 0)
			(solder_paste_margin 0)
		)
		(pad "8" smd rect
			(at -1.025 -0.975)
			(size 0.5 0.35)
			(layers "F.Cu" "F.Mask" "F.Paste")
			(net "+3.3V")
			(solder_mask_margin 0)
			(solder_paste_margin 0)
		)
	)
	(footprint "Vault:FP-CC0402-MFG"
		(layer "F.Cu")
		(at 205.4261 105.8162 -90)
		(property "Reference" "C8"
			(at -2.4 0.493345 270)
			(unlocked yes)
			(layer "F.SilkS")
			(effects
				(font
					(size 0.762 0.762)
					(thickness 0.2286)
				)
				(justify left bottom)
			)
		)
		(property "Value" "4.7nF_50V_0402"
			(at 31.257845 -2.1089 0)
			(unlocked yes)
			(layer "F.SilkS")
			(hide yes)
			(effects
				(font
					(size 0.762 0.762)
					(thickness 0.2286)
				)
				(justify left bottom)
			)
		)
		(sheetname "POWER")
		(sheetfile "POWER.kicad_sch")
		(duplicate_pad_numbers_are_jumpers no)
		(fp_line
			(start 0.51967 0.68067)
			(end -0.53033 0.68067)
			(stroke
				(width 0.2)
				(type solid)
			)
			(layer "F.SilkS")
		)
		(fp_line
			(start 0.525 -0.675)
			(end -0.525 -0.675)
			(stroke
				(width 0.2)
				(type solid)
			)
			(layer "F.SilkS")
		)
		(fp_line
			(start -0.875 0.475)
			(end -0.875 -0.475)
			(stroke
				(width 0.2)
				(type solid)
			)
			(layer "F.CrtYd")
		)
		(fp_line
			(start 0.875 0.475)
			(end -0.875 0.475)
			(stroke
				(width 0.2)
				(type solid)
			)
			(layer "F.CrtYd")
		)
		(fp_line
			(start 0.875 0.475)
			(end 0.875 -0.475)
			(stroke
				(width 0.2)
				(type solid)
			)
			(layer "F.CrtYd")
		)
		(fp_line
			(start 0.875 -0.475)
			(end -0.875 -0.475)
			(stroke
				(width 0.2)
				(type solid)
			)
			(layer "F.CrtYd")
		)
		(fp_line
			(start 0 0.5)
			(end 0 -0.5)
			(stroke
				(width 0.1)
				(type solid)
			)
			(layer "F.Fab")
		)
		(fp_line
			(start -0.875 0.475)
			(end -0.875 -0.475)
			(stroke
				(width 0.2)
				(type solid)
			)
			(layer "F.Fab")
		)
		(fp_line
			(start 0.875 0.475)
			(end -0.875 0.475)
			(stroke
				(width 0.2)
				(type solid)
			)
			(layer "F.Fab")
		)
		(fp_line
			(start 0.875 0.475)
			(end 0.875 -0.475)
			(stroke
				(width 0.2)
				(type solid)
			)
			(layer "F.Fab")
		)
		(fp_line
			(start 0.5 0)
			(end -0.5 0)
			(stroke
				(width 0.1)
				(type solid)
			)
			(layer "F.Fab")
		)
		(fp_line
			(start 0.875 -0.475)
			(end -0.875 -0.475)
			(stroke
				(width 0.2)
				(type solid)
			)
			(layer "F.Fab")
		)
		(fp_text user "${REFERENCE}"
			(at -0.00001 0.09602 270)
			(unlocked yes)
			(layer "F.Fab")
			(effects
				(font
					(face "Arial")
					(size 0.63 0.63)
					(thickness 0.1)
				)
				(justify left bottom)
			)
		)
		(pad "1" smd rect
			(at -0.5 0 270)
			(size 0.5 0.5)
			(layers "F.Cu" "F.Mask" "F.Paste")
			(net "P5V_SENSE")
			(solder_mask_margin 0)
			(solder_paste_margin 0)
		)
		(pad "2" smd rect
			(at 0.5 0 270)
			(size 0.5 0.5)
			(layers "F.Cu" "F.Mask" "F.Paste")
			(net "P5V_FB")
			(solder_mask_margin 0)
			(solder_paste_margin 0)
		)
	)
)
